# S9S_MB_2U (Grand Teton) — schematic netlist excerpt (pin names and nets, part order shuffled) for the footprints in the layout excerpt that follows; sources: Cadence DE-HDL packaged netlist, KiCad conversion of 03242023_DA0F0TMBIJ0_F0T_Motherboard_J_brd_V01_OCP.brd

R3322  Q_RES  4.7K 1% CHIP  pkg 0402LF  page 212 : A = P3V3_AUX ; B = CLK_GEN2_GPU_FPGA_OE_R2_N
PC216  Q_CAP  3300PF 50V 10% X7R  pkg 0402  page 274 : A = SH_PVCCFA_EHV_CPU0_R ; B = VSENSE_PVCCFA_EHV_CPU0_DN

(kicad_pcb
	(version 20260206)
	(generator "pcbnew")
	(generator_version "10.0")
	(general
		(thickness 1.6)
		(legacy_teardrops no)
	)
	(paper "A4")
	(title_block
		(title "03242023_DA0F0TMBIJ0_F0T_Motherboard_J_brd_V01_OCP.brd")
		(comment 1 "Grand Teton / footprints 365-366 of 6105")
	)
	(layers
		(0 "F.Cu" signal "TOP")
		(4 "In1.Cu" signal "GND")
		(6 "In2.Cu" signal "IN1")
		(8 "In3.Cu" signal "GND1")
		(10 "In4.Cu" signal "IN2")
		(12 "In5.Cu" signal "GND2")
		(14 "In6.Cu" signal "IN3")
		(16 "In7.Cu" signal "GND3")
		(18 "In8.Cu" signal "VCC")
		(20 "In9.Cu" signal "VCC1")
		(22 "In10.Cu" signal "GND4")
		(24 "In11.Cu" signal "IN4")
		(26 "In12.Cu" signal "GND5")
		(28 "In13.Cu" signal "IN5")
		(30 "In14.Cu" signal "GND6")
		(32 "In15.Cu" signal "IN6")
		(34 "In16.Cu" signal "GND7")
		(2 "B.Cu" signal "BOTTOM")
		(9 "F.Adhes" user "F.Adhesive")
		(11 "B.Adhes" user "B.Adhesive")
		(13 "F.Paste" user "Package Geometry/Pastemask Top")
		(15 "B.Paste" user "Package Geometry/Pastemask Bottom")
		(5 "F.SilkS" user "Ref Des/Silkscreen Top")
		(7 "B.SilkS" user "Ref Des/Silkscreen Bottom")
		(1 "F.Mask" user "Board Geometry/Soldermask Top")
		(3 "B.Mask" user "Board Geometry/Soldermask Bottom")
		(17 "Dwgs.User" user "User.Drawings")
		(19 "Cmts.User" user "User.Comments")
		(21 "Eco1.User" user "User.Eco1")
		(23 "Eco2.User" user "User.Eco2")
		(25 "Edge.Cuts" user "Board Geometry/Outline")
		(27 "Margin" user)
		(31 "F.CrtYd" user "Package Geometry/Place Bound Top")
		(29 "B.CrtYd" user "Package Geometry/Place Bound Bottom")
		(35 "F.Fab" user "Ref Des/Assembly Top")
		(33 "B.Fab" user "Ref Des/Assembly Bottom")
	)
	(footprint ""
		(layer "F.Cu")
		(at 116.159534 -38.065456)
		(property "Reference" "R3322"
			(at 0 0 0)
			(layer "F.SilkS")
			(hide yes)
			(effects
				(font
					(size 1.27 1.27)
				)
			)
		)
		(property "Value" ""
			(at 0 0 0)
			(layer "F.Fab")
			(effects
				(font
					(size 1.27 1.27)
				)
			)
		)
		(duplicate_pad_numbers_are_jumpers no)
		(fp_line
			(start -0.7874 -0.4064)
			(end 0.7874 -0.4064)
			(stroke
				(width 0.1524)
				(type default)
			)
			(layer "F.SilkS")
		)
		(fp_line
			(start -0.7874 0.4064)
			(end -0.7874 -0.4064)
			(stroke
				(width 0.1524)
				(type default)
			)
			(layer "F.SilkS")
		)
		(fp_line
			(start 0.7874 -0.4064)
			(end 0.7874 0.4064)
			(stroke
				(width 0.1524)
				(type default)
			)
			(layer "F.SilkS")
		)
		(fp_line
			(start 0.7874 0.4064)
			(end -0.7874 0.4064)
			(stroke
				(width 0.1524)
				(type default)
			)
			(layer "F.SilkS")
		)
		(fp_line
			(start -0.67945 -0.305054)
			(end -0.12065 -0.305054)
			(stroke
				(width 0.1)
				(type default)
			)
			(layer "F.Fab")
		)
		(fp_line
			(start -0.67945 0.3048)
			(end -0.67945 -0.305054)
			(stroke
				(width 0.1)
				(type default)
			)
			(layer "F.Fab")
		)
		(fp_line
			(start -0.12065 -0.305054)
			(end -0.12065 -0.2794)
			(stroke
				(width 0.1)
				(type default)
			)
			(layer "F.Fab")
		)
		(fp_line
			(start -0.12065 -0.2794)
			(end 0.12065 -0.2794)
			(stroke
				(width 0.1)
				(type default)
			)
			(layer "F.Fab")
		)
		(fp_line
			(start -0.12065 0.2794)
			(end -0.12065 0.3048)
			(stroke
				(width 0.1)
				(type default)
			)
			(layer "F.Fab")
		)
		(fp_line
			(start -0.12065 0.3048)
			(end -0.67945 0.3048)
			(stroke
				(width 0.1)
				(type default)
			)
			(layer "F.Fab")
		)
		(fp_line
			(start 0.120396 0.2794)
			(end -0.12065 0.2794)
			(stroke
				(width 0.1)
				(type default)
			)
			(layer "F.Fab")
		)
		(fp_line
			(start 0.120396 0.3048)
			(end 0.120396 0.2794)
			(stroke
				(width 0.1)
				(type default)
			)
			(layer "F.Fab")
		)
		(fp_line
			(start 0.12065 -0.3048)
			(end 0.67945 -0.3048)
			(stroke
				(width 0.1)
				(type default)
			)
			(layer "F.Fab")
		)
		(fp_line
			(start 0.12065 -0.2794)
			(end 0.12065 -0.3048)
			(stroke
				(width 0.1)
				(type default)
			)
			(layer "F.Fab")
		)
		(fp_line
			(start 0.67945 -0.3048)
			(end 0.67945 0.3048)
			(stroke
				(width 0.1)
				(type default)
			)
			(layer "F.Fab")
		)
		(fp_line
			(start 0.67945 0.3048)
			(end 0.120396 0.3048)
			(stroke
				(width 0.1)
				(type default)
			)
			(layer "F.Fab")
		)
		(pad "1" smd circle
			(at -0.40005 0)
			(size 0 0)
			(layers "F.Cu" "F.Mask" "F.Paste")
			(net "P3V3_AUX")
		)
		(pad "2" smd circle
			(at 0.40005 0)
			(size 0 0)
			(layers "F.Cu" "F.Mask" "F.Paste")
			(net "CLK_GEN2_GPU_FPGA_OE_R2_N")
		)
	)
	(footprint ""
		(layer "F.Cu")
		(at 422.478962 -139.797028)
		(property "Reference" "PC216"
			(at 0 0 0)
			(layer "F.SilkS")
			(hide yes)
			(effects
				(font
					(size 1.27 1.27)
				)
			)
		)
		(property "Value" ""
			(at 0 0 0)
			(layer "F.Fab")
			(effects
				(font
					(size 1.27 1.27)
				)
			)
		)
		(duplicate_pad_numbers_are_jumpers no)
		(fp_line
			(start -0.7874 -0.4064)
			(end 0.7874 -0.4064)
			(stroke
				(width 0.1524)
				(type default)
			)
			(layer "F.SilkS")
		)
		(fp_line
			(start -0.7874 0.4064)
			(end -0.7874 -0.4064)
			(stroke
				(width 0.1524)
				(type default)
			)
			(layer "F.SilkS")
		)
		(fp_line
			(start 0.7874 -0.4064)
			(end 0.7874 0.4064)
			(stroke
				(width 0.1524)
				(type default)
			)
			(layer "F.SilkS")
		)
		(fp_line
			(start 0.7874 0.4064)
			(end -0.7874 0.4064)
			(stroke
				(width 0.1524)
				(type default)
			)
			(layer "F.SilkS")
		)
		(fp_line
			(start -0.67945 -0.305054)
			(end -0.12065 -0.305054)
			(stroke
				(width 0.1)
				(type default)
			)
			(layer "F.Fab")
		)
		(fp_line
			(start -0.67945 0.3048)
			(end -0.67945 -0.305054)
			(stroke
				(width 0.1)
				(type default)
			)
			(layer "F.Fab")
		)
		(fp_line
			(start -0.12065 -0.305054)
			(end -0.12065 -0.2794)
			(stroke
				(width 0.1)
				(type default)
			)
			(layer "F.Fab")
		)
		(fp_line
			(start -0.12065 -0.2794)
			(end 0.12065 -0.2794)
			(stroke
				(width 0.1)
				(type default)
			)
			(layer "F.Fab")
		)
		(fp_line
			(start -0.12065 0.2794)
			(end -0.12065 0.3048)
			(stroke
				(width 0.1)
				(type default)
			)
			(layer "F.Fab")
		)
		(fp_line
			(start -0.12065 0.3048)
			(end -0.67945 0.3048)
			(stroke
				(width 0.1)
				(type default)
			)
			(layer "F.Fab")
		)
		(fp_line
			(start 0.120396 0.2794)
			(end -0.12065 0.2794)
			(stroke
				(width 0.1)
				(type default)
			)
			(layer "F.Fab")
		)
		(fp_line
			(start 0.120396 0.3048)
			(end 0.120396 0.2794)
			(stroke
				(width 0.1)
				(type default)
			)
			(layer "F.Fab")
		)
		(fp_line
			(start 0.12065 -0.3048)
			(end 0.67945 -0.3048)
			(stroke
				(width 0.1)
				(type default)
			)
			(layer "F.Fab")
		)
		(fp_line
			(start 0.12065 -0.2794)
			(end 0.12065 -0.3048)
			(stroke
				(width 0.1)
				(type default)
			)
			(layer "F.Fab")
		)
		(fp_line
			(start 0.67945 -0.3048)
			(end 0.67945 0.3048)
			(stroke
				(width 0.1)
				(type default)
			)
			(layer "F.Fab")
		)
		(fp_line
			(start 0.67945 0.3048)
			(end 0.120396 0.3048)
			(stroke
				(width 0.1)
				(type default)
			)
			(layer "F.Fab")
		)
		(pad "1" smd circle
			(at -0.40005 0)
			(size 0 0)
			(layers "F.Cu" "F.Mask" "F.Paste")
			(net "SH_PVCCFA_EHV_CPU0_R")
		)
		(pad "2" smd circle
			(at 0.40005 0)
			(size 0 0)
			(layers "F.Cu" "F.Mask" "F.Paste")
			(net "VSENSE_PVCCFA_EHV_CPU0_DN")
		)
	)
)
